(kicad_pcb
	(version 20260206)
	(generator "pcbnew")
	(generator_version "10.0")
	(general
		(thickness 1.6)
		(legacy_teardrops no)
	)
	(paper "A4")
	(title_block
		(title "04192023_DAF0TMB3IC0_F0TG_MB_C_brd_V02_OCP.brd")
		(comment 1 "Grand Teton / footprints 1113-1119 of 8354")
	)
	(layers
		(0 "F.Cu" signal "TOP")
		(4 "In1.Cu" signal "GND")
		(6 "In2.Cu" signal "IN1")
		(8 "In3.Cu" signal "GND1")
		(10 "In4.Cu" signal "IN2")
		(12 "In5.Cu" signal "GND2")
		(14 "In6.Cu" signal "IN3")
		(16 "In7.Cu" signal "GND3")
		(18 "In8.Cu" signal "VCC")
		(20 "In9.Cu" signal "VCC1")
		(22 "In10.Cu" signal "GND4")
		(24 "In11.Cu" signal "IN4")
		(26 "In12.Cu" signal "GND5")
		(28 "In13.Cu" signal "IN5")
		(30 "In14.Cu" signal "GND6")
		(32 "In15.Cu" signal "IN6")
		(34 "In16.Cu" signal "GND7")
		(2 "B.Cu" signal "BOTTOM")
		(9 "F.Adhes" user "F.Adhesive")
		(11 "B.Adhes" user "B.Adhesive")
		(13 "F.Paste" user "Package Geometry/Pastemask Top")
		(15 "B.Paste" user "Package Geometry/Pastemask Bottom")
		(5 "F.SilkS" user "Ref Des/Silkscreen Top")
		(7 "B.SilkS" user "Ref Des/Silkscreen Bottom")
		(1 "F.Mask" user "Board Geometry/Soldermask Top")
		(3 "B.Mask" user "Board Geometry/Soldermask Bottom")
		(17 "Dwgs.User" user "User.Drawings")
		(19 "Cmts.User" user "User.Comments")
		(21 "Eco1.User" user "User.Eco1")
		(23 "Eco2.User" user "User.Eco2")
		(25 "Edge.Cuts" user "Board Geometry/Outline")
		(27 "Margin" user)
		(31 "F.CrtYd" user "Package Geometry/Place Bound Top")
		(29 "B.CrtYd" user "Package Geometry/Place Bound Bottom")
		(35 "F.Fab" user "Ref Des/Assembly Top")
		(33 "B.Fab" user "Ref Des/Assembly Bottom")
	)
	(footprint ""
		(layer "F.Cu")
		(at 262.848852 -137.103104 -90)
		(property "Reference" "C1103"
			(at 0 0 270)
			(layer "F.SilkS")
			(hide yes)
			(effects
				(font
					(size 1.27 1.27)
				)
			)
		)
		(property "Value" ""
			(at 0 0 270)
			(layer "F.Fab")
			(effects
				(font
					(size 1.27 1.27)
				)
			)
		)
		(duplicate_pad_numbers_are_jumpers no)
		(fp_line
			(start -0.7874 0.4064)
			(end -0.7874 -0.4064)
			(stroke
				(width 0.1524)
				(type default)
			)
			(layer "F.SilkS")
		)
		(fp_line
			(start 0.7874 0.4064)
			(end -0.7874 0.4064)
			(stroke
				(width 0.1524)
				(type default)
			)
			(layer "F.SilkS")
		)
		(fp_line
			(start -0.7874 -0.4064)
			(end 0.7874 -0.4064)
			(stroke
				(width 0.1524)
				(type default)
			)
			(layer "F.SilkS")
		)
		(fp_line
			(start 0.7874 -0.4064)
			(end 0.7874 0.4064)
			(stroke
				(width 0.1524)
				(type default)
			)
			(layer "F.SilkS")
		)
		(fp_line
			(start -0.67945 0.3048)
			(end -0.67945 -0.305054)
			(stroke
				(width 0.1)
				(type default)
			)
			(layer "F.Fab")
		)
		(fp_line
			(start -0.12065 0.3048)
			(end -0.67945 0.3048)
			(stroke
				(width 0.1)
				(type default)
			)
			(layer "F.Fab")
		)
		(fp_line
			(start 0.120396 0.3048)
			(end 0.120396 0.2794)
			(stroke
				(width 0.1)
				(type default)
			)
			(layer "F.Fab")
		)
		(fp_line
			(start 0.67945 0.3048)
			(end 0.120396 0.3048)
			(stroke
				(width 0.1)
				(type default)
			)
			(layer "F.Fab")
		)
		(fp_line
			(start -0.12065 0.2794)
			(end -0.12065 0.3048)
			(stroke
				(width 0.1)
				(type default)
			)
			(layer "F.Fab")
		)
		(fp_line
			(start 0.120396 0.2794)
			(end -0.12065 0.2794)
			(stroke
				(width 0.1)
				(type default)
			)
			(layer "F.Fab")
		)
		(fp_line
			(start -0.12065 -0.2794)
			(end 0.12065 -0.2794)
			(stroke
				(width 0.1)
				(type default)
			)
			(layer "F.Fab")
		)
		(fp_line
			(start 0.12065 -0.2794)
			(end 0.12065 -0.3048)
			(stroke
				(width 0.1)
				(type default)
			)
			(layer "F.Fab")
		)
		(fp_line
			(start 0.12065 -0.3048)
			(end 0.67945 -0.3048)
			(stroke
				(width 0.1)
				(type default)
			)
			(layer "F.Fab")
		)
		(fp_line
			(start 0.67945 -0.3048)
			(end 0.67945 0.3048)
			(stroke
				(width 0.1)
				(type default)
			)
			(layer "F.Fab")
		)
		(fp_line
			(start -0.67945 -0.305054)
			(end -0.12065 -0.305054)
			(stroke
				(width 0.1)
				(type default)
			)
			(layer "F.Fab")
		)
		(fp_line
			(start -0.12065 -0.305054)
			(end -0.12065 -0.2794)
			(stroke
				(width 0.1)
				(type default)
			)
			(layer "F.Fab")
		)
		(pad "1" smd circle
			(at -0.40005 0 270)
			(size 0 0)
			(layers "F.Cu" "F.Mask" "F.Paste")
			(net "PVDD18_S5_P0")
		)
		(pad "2" smd circle
			(at 0.40005 0 270)
			(size 0 0)
			(layers "F.Cu" "F.Mask" "F.Paste")
			(net "GND")
		)
	)
	(footprint ""
		(layer "F.Cu")
		(at 170.979846 -383.11709 180)
		(property "Reference" "R887"
			(at 0 0 180)
			(layer "F.SilkS")
			(hide yes)
			(effects
				(font
					(size 1.27 1.27)
				)
			)
		)
		(property "Value" ""
			(at 0 0 180)
			(layer "F.Fab")
			(effects
				(font
					(size 1.27 1.27)
				)
			)
		)
		(duplicate_pad_numbers_are_jumpers no)
		(fp_line
			(start 0.32512 0.175006)
			(end -0.32512 0.175006)
			(stroke
				(width 0.1)
				(type default)
			)
			(layer "F.Fab")
		)
		(fp_line
			(start 0.32512 -0.175006)
			(end 0.32512 0.175006)
			(stroke
				(width 0.1)
				(type default)
			)
			(layer "F.Fab")
		)
		(fp_line
			(start -0.32512 0.175006)
			(end -0.32512 -0.175006)
			(stroke
				(width 0.1)
				(type default)
			)
			(layer "F.Fab")
		)
		(fp_line
			(start -0.32512 -0.175006)
			(end 0.32512 -0.175006)
			(stroke
				(width 0.1)
				(type default)
			)
			(layer "F.Fab")
		)
		(pad "1" smd rect
			(at -0.2667 0 180)
			(size 0.3048 0.381)
			(layers "F.Cu" "F.Mask" "F.Paste")
			(net "P1V8_CPU1_RT_1D")
		)
		(pad "2" smd rect
			(at 0.2667 0)
			(size 0.3048 0.381)
			(layers "F.Cu" "F.Mask" "F.Paste")
			(net "RT_CPU1_P2_ADDR1")
		)
	)
	(footprint ""
		(layer "F.Cu")
		(at 317.896748 -115.108228 180)
		(property "Reference" "R86"
			(at 0 0 180)
			(layer "F.SilkS")
			(hide yes)
			(effects
				(font
					(size 1.27 1.27)
				)
			)
		)
		(property "Value" ""
			(at 0 0 180)
			(layer "F.Fab")
			(effects
				(font
					(size 1.27 1.27)
				)
			)
		)
		(duplicate_pad_numbers_are_jumpers no)
		(fp_line
			(start 0.7874 0.4064)
			(end -0.7874 0.4064)
			(stroke
				(width 0.1524)
				(type default)
			)
			(layer "F.SilkS")
		)
		(fp_line
			(start 0.7874 -0.4064)
			(end 0.7874 0.4064)
			(stroke
				(width 0.1524)
				(type default)
			)
			(layer "F.SilkS")
		)
		(fp_line
			(start -0.7874 0.4064)
			(end -0.7874 -0.4064)
			(stroke
				(width 0.1524)
				(type default)
			)
			(layer "F.SilkS")
		)
		(fp_line
			(start -0.7874 -0.4064)
			(end 0.7874 -0.4064)
			(stroke
				(width 0.1524)
				(type default)
			)
			(layer "F.SilkS")
		)
		(fp_line
			(start 0.67945 0.3048)
			(end 0.120396 0.3048)
			(stroke
				(width 0.1)
				(type default)
			)
			(layer "F.Fab")
		)
		(fp_line
			(start 0.67945 -0.3048)
			(end 0.67945 0.3048)
			(stroke
				(width 0.1)
				(type default)
			)
			(layer "F.Fab")
		)
		(fp_line
			(start 0.12065 -0.2794)
			(end 0.12065 -0.3048)
			(stroke
				(width 0.1)
				(type default)
			)
			(layer "F.Fab")
		)
		(fp_line
			(start 0.12065 -0.3048)
			(end 0.67945 -0.3048)
			(stroke
				(width 0.1)
				(type default)
			)
			(layer "F.Fab")
		)
		(fp_line
			(start 0.120396 0.3048)
			(end 0.120396 0.2794)
			(stroke
				(width 0.1)
				(type default)
			)
			(layer "F.Fab")
		)
		(fp_line
			(start 0.120396 0.2794)
			(end -0.12065 0.2794)
			(stroke
				(width 0.1)
				(type default)
			)
			(layer "F.Fab")
		)
		(fp_line
			(start -0.12065 0.3048)
			(end -0.67945 0.3048)
			(stroke
				(width 0.1)
				(type default)
			)
			(layer "F.Fab")
		)
		(fp_line
			(start -0.12065 0.2794)
			(end -0.12065 0.3048)
			(stroke
				(width 0.1)
				(type default)
			)
			(layer "F.Fab")
		)
		(fp_line
			(start -0.12065 -0.2794)
			(end 0.12065 -0.2794)
			(stroke
				(width 0.1)
				(type default)
			)
			(layer "F.Fab")
		)
		(fp_line
			(start -0.12065 -0.305054)
			(end -0.12065 -0.2794)
			(stroke
				(width 0.1)
				(type default)
			)
			(layer "F.Fab")
		)
		(fp_line
			(start -0.67945 0.3048)
			(end -0.67945 -0.305054)
			(stroke
				(width 0.1)
				(type default)
			)
			(layer "F.Fab")
		)
		(fp_line
			(start -0.67945 -0.305054)
			(end -0.12065 -0.305054)
			(stroke
				(width 0.1)
				(type default)
			)
			(layer "F.Fab")
		)
		(pad "1" smd circle
			(at -0.40005 0 180)
			(size 0 0)
			(layers "F.Cu" "F.Mask" "F.Paste")
			(net "SMB_FRU_3V3AUX_SDA")
		)
		(pad "2" smd circle
			(at 0.40005 0 180)
			(size 0 0)
			(layers "F.Cu" "F.Mask" "F.Paste")
			(net "SMB_FRU_3V3AUX_R1_SDA")
		)
	)
	(footprint ""
		(layer "F.Cu")
		(at 447.237866 -405.7777 180)
		(property "Reference" "PC6558_1"
			(at 0 0 180)
			(layer "F.SilkS")
			(hide yes)
			(effects
				(font
					(size 1.27 1.27)
				)
			)
		)
		(property "Value" ""
			(at 0 0 180)
			(layer "F.Fab")
			(effects
				(font
					(size 1.27 1.27)
				)
			)
		)
		(duplicate_pad_numbers_are_jumpers no)
		(fp_line
			(start 1.524 0.762)
			(end -1.524 0.762)
			(stroke
				(width 0.1524)
				(type default)
			)
			(layer "F.SilkS")
		)
		(fp_line
			(start 1.524 -0.762)
			(end 1.524 0.762)
			(stroke
				(width 0.1524)
				(type default)
			)
			(layer "F.SilkS")
		)
		(fp_line
			(start -1.524 0.762)
			(end -1.524 -0.762)
			(stroke
				(width 0.1524)
				(type default)
			)
			(layer "F.SilkS")
		)
		(fp_line
			(start -1.524 -0.762)
			(end 1.524 -0.762)
			(stroke
				(width 0.1524)
				(type default)
			)
			(layer "F.SilkS")
		)
		(fp_line
			(start 1.1049 0.724916)
			(end 1.1049 -0.724916)
			(stroke
				(width 0.1)
				(type default)
			)
			(layer "F.Fab")
		)
		(fp_line
			(start 1.1049 -0.724916)
			(end -1.1049 -0.724916)
			(stroke
				(width 0.1)
				(type default)
			)
			(layer "F.Fab")
		)
		(fp_line
			(start -1.1049 0.724916)
			(end 1.1049 0.724916)
			(stroke
				(width 0.1)
				(type default)
			)
			(layer "F.Fab")
		)
		(fp_line
			(start -1.1049 -0.724916)
			(end -1.1049 0.724916)
			(stroke
				(width 0.1)
				(type default)
			)
			(layer "F.Fab")
		)
		(pad "1" smd rect
			(at -0.889 0)
			(size 1.016 1.27)
			(layers "F.Cu" "F.Mask" "F.Paste")
			(net "SW_P12V_AUX_P0V9_RETIMER_CPU0_FLT")
		)
		(pad "2" smd rect
			(at 0.889 0)
			(size 1.016 1.27)
			(layers "F.Cu" "F.Mask" "F.Paste")
			(net "GND")
		)
	)
	(footprint ""
		(layer "F.Cu")
		(at 446.52438 -65.767458 -90)
		(property "Reference" "C60"
			(at 0 0 270)
			(layer "F.SilkS")
			(hide yes)
			(effects
				(font
					(size 1.27 1.27)
				)
			)
		)
		(property "Value" ""
			(at 0 0 270)
			(layer "F.Fab")
			(effects
				(font
					(size 1.27 1.27)
				)
			)
		)
		(duplicate_pad_numbers_are_jumpers no)
		(fp_line
			(start -1.524 0.762)
			(end -1.524 -0.762)
			(stroke
				(width 0.1524)
				(type default)
			)
			(layer "F.SilkS")
		)
		(fp_line
			(start 1.524 0.762)
			(end -1.524 0.762)
			(stroke
				(width 0.1524)
				(type default)
			)
			(layer "F.SilkS")
		)
		(fp_line
			(start -1.524 -0.762)
			(end 1.524 -0.762)
			(stroke
				(width 0.1524)
				(type default)
			)
			(layer "F.SilkS")
		)
		(fp_line
			(start 1.524 -0.762)
			(end 1.524 0.762)
			(stroke
				(width 0.1524)
				(type default)
			)
			(layer "F.SilkS")
		)
		(fp_line
			(start -1.1049 0.724916)
			(end 1.1049 0.724916)
			(stroke
				(width 0.1)
				(type default)
			)
			(layer "F.Fab")
		)
		(fp_line
			(start 1.1049 0.724916)
			(end 1.1049 -0.724916)
			(stroke
				(width 0.1)
				(type default)
			)
			(layer "F.Fab")
		)
		(fp_line
			(start -1.1049 -0.724916)
			(end -1.1049 0.724916)
			(stroke
				(width 0.1)
				(type default)
			)
			(layer "F.Fab")
		)
		(fp_line
			(start 1.1049 -0.724916)
			(end -1.1049 -0.724916)
			(stroke
				(width 0.1)
				(type default)
			)
			(layer "F.Fab")
		)
		(pad "1" smd rect
			(at -0.889 0 90)
			(size 1.016 1.27)
			(layers "F.Cu" "F.Mask" "F.Paste")
			(net "P3V3_AUX")
		)
		(pad "2" smd rect
			(at 0.889 0 90)
			(size 1.016 1.27)
			(layers "F.Cu" "F.Mask" "F.Paste")
			(net "GND")
		)
	)
	(footprint ""
		(layer "F.Cu")
		(at 69.85127 -152.33269 90)
		(property "Reference" "PU3"
			(at 4.542536 -1.890014 0)
			(unlocked yes)
			(layer "F.SilkS")
			(effects
				(font
					(size 0.7874 0.5842)
					(thickness 0.1524)
				)
				(justify left)
			)
		)
		(property "Value" ""
			(at 0 0 90)
			(layer "F.Fab")
			(effects
				(font
					(size 1.27 1.27)
				)
			)
		)
		(duplicate_pad_numbers_are_jumpers no)
		(fp_line
			(start 1.549908 -2.050034)
			(end 0.5842 -2.050034)
			(stroke
				(width 0.1524)
				(type default)
			)
			(layer "F.SilkS")
		)
		(fp_line
			(start -0.5842 -2.050034)
			(end -1.549908 -2.050034)
			(stroke
				(width 0.1524)
				(type default)
			)
			(layer "F.SilkS")
		)
		(fp_line
			(start -1.549908 -2.050034)
			(end -1.549908 -1.9812)
			(stroke
				(width 0.1524)
				(type default)
			)
			(layer "F.SilkS")
		)
		(fp_line
			(start 1.549908 -1.9812)
			(end 1.549908 -2.050034)
			(stroke
				(width 0.1524)
				(type default)
			)
			(layer "F.SilkS")
		)
		(fp_line
			(start -1.549908 1.9812)
			(end -1.549908 2.050034)
			(stroke
				(width 0.1524)
				(type default)
			)
			(layer "F.SilkS")
		)
		(fp_line
			(start 0 2.050034)
			(end 1.549908 2.050034)
			(stroke
				(width 0.1524)
				(type default)
			)
			(layer "F.SilkS")
		)
		(fp_line
			(start -1.549908 2.050034)
			(end -0.5842 2.050034)
			(stroke
				(width 0.1524)
				(type default)
			)
			(layer "F.SilkS")
		)
		(fp_poly
			(pts
				(xy -1.991868 -1.787398) (xy -3.007868 -1.279398) (xy -3.007868 -2.295398)
			)
			(stroke
				(width 0)
				(type default)
			)
			(fill yes)
			(layer "F.SilkS")
		)
		(fp_line
			(start 1.549908 -2.050034)
			(end -1.549908 -2.050034)
			(stroke
				(width 0.1)
				(type default)
			)
			(layer "F.Fab")
		)
		(fp_line
			(start -1.549908 -2.050034)
			(end -1.549908 2.050034)
			(stroke
				(width 0.1)
				(type default)
			)
			(layer "F.Fab")
		)
		(fp_line
			(start 1.549908 2.050034)
			(end 1.549908 -2.050034)
			(stroke
				(width 0.1)
				(type default)
			)
			(layer "F.Fab")
		)
		(fp_line
			(start -1.549908 2.050034)
			(end 1.549908 2.050034)
			(stroke
				(width 0.1)
				(type default)
			)
			(layer "F.Fab")
		)
		(fp_poly
			(pts
				(xy -2.9464 -2.208022) (xy -2.9464 -1.192022) (xy -1.9304 -1.700022)
			)
			(stroke
				(width 0)
				(type default)
			)
			(fill yes)
			(layer "F.Fab")
		)
		(pad "1" smd circle
			(at -1.35001 -1.700022 90)
			(size 0 0)
			(layers "F.Cu" "F.Mask" "F.Paste")
			(net "SW_PVDD18_S5_P1_BST")
		)
		(pad "2" smd rect
			(at -1.400048 -1.199896 180)
			(size 0.1778 0.8128)
			(layers "F.Cu" "F.Mask" "F.Paste")
			(net "GND")
		)
		(pad "3" smd rect
			(at -1.400048 -0.8001 180)
			(size 0.1778 0.8128)
			(layers "F.Cu" "F.Mask" "F.Paste")
			(net "PVDD18_S5_P1_CS")
		)
		(pad "4" smd rect
			(at -1.400048 -0.40005 180)
			(size 0.1778 0.8128)
			(layers "F.Cu" "F.Mask" "F.Paste")
			(net "PVDD18_S5_P1_MODE")
		)
		(pad "5" smd rect
			(at -1.400048 0 180)
			(size 0.1778 0.8128)
			(layers "F.Cu" "F.Mask" "F.Paste")
			(net "PVDD18_S5_P1_REF")
		)
		(pad "6" smd rect
			(at -1.400048 0.40005 180)
			(size 0.1778 0.8128)
			(layers "F.Cu" "F.Mask" "F.Paste")
			(net "PVDD18_SS_P1_RGND")
		)
		(pad "7" smd rect
			(at -1.400048 0.8001 180)
			(size 0.1778 0.8128)
			(layers "F.Cu" "F.Mask" "F.Paste")
			(net "PVDD18_S5_P1_FB")
		)
		(pad "8" smd rect
			(at -1.400048 1.199896 180)
			(size 0.1778 0.8128)
			(layers "F.Cu" "F.Mask" "F.Paste")
			(net "PVDD18_S5_P1_EN")
		)
		(pad "9" smd rect
			(at -1.400048 1.700022 180)
			(size 0.3048 0.8128)
			(layers "F.Cu" "F.Mask" "F.Paste")
			(net "PWRGD_PVDD18_S5_P1")
		)
		(pad "10" smd rect
			(at -0.299974 1.299972 90)
			(size 0.3048 2.0066)
			(layers "F.Cu" "F.Mask" "F.Paste")
			(net "SW_P12V_AUX_PVDD18_S5_P1_FLT")
		)
		(pad "11_18" smd circle
			(at 1.175004 0.275082 90)
			(size 0 0)
			(layers "F.Cu" "F.Mask" "F.Paste")
			(net "GND")
		)
		(pad "19" smd rect
			(at 1.400048 -1.700022)
			(size 0.3048 0.8128)
			(layers "F.Cu" "F.Mask" "F.Paste")
			(net "PVDD18_S5_P1_VCC")
		)
		(pad "20" smd rect
			(at 0.299974 -1.299972 90)
			(size 0.3048 2.0066)
			(layers "F.Cu" "F.Mask" "F.Paste")
			(net "SW_PVDD18_S5_P1_SW")
		)
		(pad "21" smd rect
			(at -0.299974 -1.299972 90)
			(size 0.3048 2.0066)
			(layers "F.Cu" "F.Mask" "F.Paste")
			(net "SW_P12V_AUX_PVDD18_S5_P1_FLT")
		)
	)
	(footprint ""
		(layer "F.Cu")
		(at 147.16379 -98.755708 90)
		(property "Reference" "C1880"
			(at 0 0 90)
			(layer "F.SilkS")
			(hide yes)
			(effects
				(font
					(size 1.27 1.27)
				)
			)
		)
		(property "Value" ""
			(at 0 0 90)
			(layer "F.Fab")
			(effects
				(font
					(size 1.27 1.27)
				)
			)
		)
		(duplicate_pad_numbers_are_jumpers no)
		(fp_line
			(start 0.7874 -0.4064)
			(end 0.7874 0.4064)
			(stroke
				(width 0.1524)
				(type default)
			)
			(layer "F.SilkS")
		)
		(fp_line
			(start -0.7874 -0.4064)
			(end 0.7874 -0.4064)
			(stroke
				(width 0.1524)
				(type default)
			)
			(layer "F.SilkS")
		)
		(fp_line
			(start 0.7874 0.4064)
			(end -0.7874 0.4064)
			(stroke
				(width 0.1524)
				(type default)
			)
			(layer "F.SilkS")
		)
		(fp_line
			(start -0.7874 0.4064)
			(end -0.7874 -0.4064)
			(stroke
				(width 0.1524)
				(type default)
			)
			(layer "F.SilkS")
		)
		(fp_line
			(start -0.12065 -0.305054)
			(end -0.12065 -0.2794)
			(stroke
				(width 0.1)
				(type default)
			)
			(layer "F.Fab")
		)
		(fp_line
			(start -0.67945 -0.305054)
			(end -0.12065 -0.305054)
			(stroke
				(width 0.1)
				(type default)
			)
			(layer "F.Fab")
		)
		(fp_line
			(start 0.67945 -0.3048)
			(end 0.67945 0.3048)
			(stroke
				(width 0.1)
				(type default)
			)
			(layer "F.Fab")
		)
		(fp_line
			(start 0.12065 -0.3048)
			(end 0.67945 -0.3048)
			(stroke
				(width 0.1)
				(type default)
			)
			(layer "F.Fab")
		)
		(fp_line
			(start 0.12065 -0.2794)
			(end 0.12065 -0.3048)
			(stroke
				(width 0.1)
				(type default)
			)
			(layer "F.Fab")
		)
		(fp_line
			(start -0.12065 -0.2794)
			(end 0.12065 -0.2794)
			(stroke
				(width 0.1)
				(type default)
			)
			(layer "F.Fab")
		)
		(fp_line
			(start 0.120396 0.2794)
			(end -0.12065 0.2794)
			(stroke
				(width 0.1)
				(type default)
			)
			(layer "F.Fab")
		)
		(fp_line
			(start -0.12065 0.2794)
			(end -0.12065 0.3048)
			(stroke
				(width 0.1)
				(type default)
			)
			(layer "F.Fab")
		)
		(fp_line
			(start 0.67945 0.3048)
			(end 0.120396 0.3048)
			(stroke
				(width 0.1)
				(type default)
			)
			(layer "F.Fab")
		)
		(fp_line
			(start 0.120396 0.3048)
			(end 0.120396 0.2794)
			(stroke
				(width 0.1)
				(type default)
			)
			(layer "F.Fab")
		)
		(fp_line
			(start -0.12065 0.3048)
			(end -0.67945 0.3048)
			(stroke
				(width 0.1)
				(type default)
			)
			(layer "F.Fab")
		)
		(fp_line
			(start -0.67945 0.3048)
			(end -0.67945 -0.305054)
			(stroke
				(width 0.1)
				(type default)
			)
			(layer "F.Fab")
		)
		(pad "1" smd circle
			(at -0.40005 0 90)
			(size 0 0)
			(layers "F.Cu" "F.Mask" "F.Paste")
			(net "P3V3_AUX")
		)
		(pad "2" smd circle
			(at 0.40005 0 90)
			(size 0 0)
			(layers "F.Cu" "F.Mask" "F.Paste")
			(net "GND")
		)
	)
)
